(kicad_pcb
	(version 20241229)
	(generator "pcbnew")
	(generator_version "9.0")
	(general
		(thickness 1.6296)
		(legacy_teardrops no)
	)
	(paper "A3")
	(title_block
		(title "Thunderbolt to 10GbE adapter")
		(date "2026-04-21")
		(rev "1.1.0")
		(company "Antmicro Ltd")
		(comment 1 "www.antmicro.com")
		(comment 9 "footprints 179-182 of 703")
	)
	(layers
		(0 "F.Cu" signal)
		(4 "In1.Cu" signal)
		(6 "In2.Cu" signal)
		(8 "In3.Cu" signal)
		(10 "In4.Cu" signal)
		(12 "In5.Cu" signal)
		(14 "In6.Cu" signal)
		(2 "B.Cu" signal)
		(9 "F.Adhes" user "F.Adhesive")
		(11 "B.Adhes" user "B.Adhesive")
		(13 "F.Paste" user)
		(15 "B.Paste" user)
		(5 "F.SilkS" user "F.Silkscreen")
		(7 "B.SilkS" user "B.Silkscreen")
		(1 "F.Mask" user)
		(3 "B.Mask" user)
		(17 "Dwgs.User" user "User.Drawings")
		(19 "Cmts.User" user "User.Comments")
		(21 "Eco1.User" user "User.Eco1")
		(23 "Eco2.User" user "User.Eco2")
		(25 "Edge.Cuts" user)
		(27 "Margin" user)
		(31 "F.CrtYd" user "F.Courtyard")
		(29 "B.CrtYd" user "B.Courtyard")
		(35 "F.Fab" user)
		(33 "B.Fab" user)
	)
	(footprint "antmicro-footprints:Conn_Molex_Nano-Fit_1x2_105313-2202_Horizontal"
		(layer "F.Cu")
		(at 131.146 56.804561 90)
		(descr "Molex Nano-Fit Power Connectors, 2 Pins per row")
		(tags "connector Molex Nano-Fit NanoFit top entry 2.50mm horizontal")
		(property "Reference" "J5"
			(at -0.395439 4.454 90)
			(layer "F.SilkS")
			(effects
				(font
					(size 0.7 0.7)
					(thickness 0.15)
				)
				(justify left bottom)
			)
		)
		(property "Value" "Molex_Nano-Fit_1x2_105313-2202_Horizontal"
			(at 0 5.8 90)
			(layer "F.Fab")
			(effects
				(font
					(size 0.7 0.7)
					(thickness 0.15)
				)
				(justify left bottom)
			)
		)
		(property "Datasheet" "https://tools.molex.com/pdm_docs/sd/1053132202_sd.pdf"
			(at 0 0 90)
			(layer "F.Fab")
			(hide yes)
			(effects
				(font
					(size 1.27 1.27)
					(thickness 0.15)
				)
			)
		)
		(property "Description" "Pin Header, Power, 2.5 mm, 1 Rows, 2 Contacts, Through Hole Horizontal, Nano-Fit"
			(at 0 0 90)
			(layer "F.Fab")
			(hide yes)
			(effects
				(font
					(size 1.27 1.27)
					(thickness 0.15)
				)
			)
		)
		(property "MPN" "105313-2202"
			(at 0 0 90)
			(unlocked yes)
			(layer "F.Fab")
			(hide yes)
			(effects
				(font
					(size 1 1)
					(thickness 0.15)
				)
			)
		)
		(property "Manufacturer" "Molex"
			(at 0 0 90)
			(unlocked yes)
			(layer "F.Fab")
			(hide yes)
			(effects
				(font
					(size 1 1)
					(thickness 0.15)
				)
			)
		)
		(property "Author" "Antmicro"
			(at 0 0 90)
			(unlocked yes)
			(layer "F.Fab")
			(hide yes)
			(effects
				(font
					(size 1 1)
					(thickness 0.15)
				)
			)
		)
		(property "License" "Apache-2.0"
			(at 0 0 90)
			(unlocked yes)
			(layer "F.Fab")
			(hide yes)
			(effects
				(font
					(size 1 1)
					(thickness 0.15)
				)
			)
		)
		(sheetname "/Power input/")
		(sheetfile "power_input.kicad_sch")
		(attr through_hole)
		(fp_rect
			(start 10.4 -1.7)
			(end 1.898 4.2)
			(stroke
				(width 0.15)
				(type solid)
			)
			(fill no)
			(layer "F.SilkS")
		)
		(fp_rect
			(start 1.4 -0.299)
			(end 1.899 0.299)
			(stroke
				(width 0.15)
				(type solid)
			)
			(fill no)
			(layer "F.SilkS")
		)
		(fp_rect
			(start 1.4 2.2)
			(end 1.899 2.798)
			(stroke
				(width 0.15)
				(type solid)
			)
			(fill no)
			(layer "F.SilkS")
		)
		(fp_circle
			(center 0 -1.25)
			(end 0.05 -1.25)
			(stroke
				(width 0.15)
				(type solid)
			)
			(fill yes)
			(layer "F.SilkS")
		)
		(fp_rect
			(start -1.197 -2.116)
			(end 12.042 4.624)
			(stroke
				(width 0.05)
				(type solid)
			)
			(fill no)
			(layer "F.CrtYd")
		)
		(fp_line
			(start -0.35 -1.71)
			(end -0.595 -1.465)
			(stroke
				(width 0.15)
				(type solid)
			)
			(layer "F.Fab")
		)
		(fp_rect
			(start -0.597 -1.716)
			(end 11.842 4.224)
			(stroke
				(width 0.15)
				(type solid)
			)
			(fill no)
			(layer "F.Fab")
		)
		(fp_text user "${REFERENCE}"
			(at -3.1 7.4 90)
			(layer "F.Fab")
			(effects
				(font
					(size 0.7 0.7)
					(thickness 0.15)
				)
				(justify left bottom)
			)
		)
		(fp_text user "License: Apache-2.0"
			(at -3.1 8.6 90)
			(layer "F.Fab")
			(effects
				(font
					(size 0.7 0.7)
					(thickness 0.15)
				)
				(justify left bottom)
			)
		)
		(fp_text user "Author: Antmicro"
			(at -3.1 9.8 90)
			(layer "F.Fab")
			(effects
				(font
					(size 0.7 0.7)
					(thickness 0.15)
				)
				(justify left bottom)
			)
		)
		(pad "" np_thru_hole circle
			(at 7.179 0 90)
			(size 1.7 1.7)
			(drill 1.7)
			(layers "*.Cu" "*.Mask")
		)
		(pad "" np_thru_hole circle
			(at 7.179 2.499 90)
			(size 1.7 1.7)
			(drill 1.7)
			(layers "*.Cu" "*.Mask")
		)
		(pad "1" thru_hole custom
			(at 0 0 90)
			(size 1.417157 1.417157)
			(drill 1.2)
			(layers "*.Cu" "*.Mask")
			(remove_unused_layers no)
			(net 412 "Net-(D15-C)")
			(pintype "input")
			(thermal_bridge_angle 90)
			(options
				(clearance outline)
				(anchor circle)
			)
			(primitives
				(gr_poly
					(pts
						(xy -0.85 -0.6) (xy 0.85 -0.6) (xy 0.85 0.6) (xy -0.45 0.6) (xy -0.85 0.2)
					)
					(width 0.5)
					(fill yes)
				)
			)
		)
		(pad "2" thru_hole oval
			(at 0 2.499 90)
			(size 2.2 1.7)
			(drill 1.2)
			(layers "*.Cu" "*.Mask")
			(remove_unused_layers no)
			(net 23 "GND")
			(pintype "input")
		)
	)
	(footprint "antmicro-footprints:RJ45_JTH-0024NL"
		(layer "F.Cu")
		(at 157.15 135.865 180)
		(property "Reference" "J3"
			(at 7.65 4.365 0)
			(unlocked yes)
			(layer "F.SilkS")
			(effects
				(font
					(size 0.7 0.7)
					(thickness 0.15)
				)
				(justify left bottom)
			)
		)
		(property "Value" "Bus_RJ45_JTH-0024NL"
			(at 5.06 1 180)
			(unlocked yes)
			(layer "F.Fab")
			(effects
				(font
					(size 0.7 0.7)
					(thickness 0.15)
				)
				(justify left bottom)
			)
		)
		(property "Datasheet" "https://www.mouser.com/datasheet/2/447/JTH_0024NL-3072047.pdf"
			(at 0 0 180)
			(layer "F.Fab")
			(hide yes)
			(effects
				(font
					(size 1.27 1.27)
					(thickness 0.15)
				)
			)
		)
		(property "Description" "Modular Connectors / Ethernet Connectors 1X1 TAB DOWN W/LED'S ETHERNET (NON PoE)"
			(at 0 0 180)
			(layer "F.Fab")
			(hide yes)
			(effects
				(font
					(size 1.27 1.27)
					(thickness 0.15)
				)
			)
		)
		(property "MPN" "JTH-0024NL"
			(at 0 0 180)
			(unlocked yes)
			(layer "F.Fab")
			(hide yes)
			(effects
				(font
					(size 1 1)
					(thickness 0.15)
				)
			)
		)
		(property "Manufacturer" "Pulse Electronics"
			(at 0 0 180)
			(unlocked yes)
			(layer "F.Fab")
			(hide yes)
			(effects
				(font
					(size 1 1)
					(thickness 0.15)
				)
			)
		)
		(property "Author" "Antmicro"
			(at 0 0 180)
			(unlocked yes)
			(layer "F.Fab")
			(hide yes)
			(effects
				(font
					(size 1 1)
					(thickness 0.15)
				)
			)
		)
		(property "License" "Apache-2.0"
			(at 0 0 180)
			(unlocked yes)
			(layer "F.Fab")
			(hide yes)
			(effects
				(font
					(size 1 1)
					(thickness 0.15)
				)
			)
		)
		(property ki_fp_filters "CONN18_5-2337992-8_TEC")
		(sheetname "/2xRJ45/")
		(sheetfile "2xrj45.kicad_sch")
		(attr through_hole)
		(fp_line
			(start 14 4)
			(end 14 -5.25)
			(stroke
				(width 0.1)
				(type default)
			)
			(layer "F.SilkS")
		)
		(fp_line
			(start -3.75 4)
			(end 14 4)
			(stroke
				(width 0.1)
				(type default)
			)
			(layer "F.SilkS")
		)
		(fp_line
			(start -3.75 -5.25)
			(end -3.75 4)
			(stroke
				(width 0.1)
				(type default)
			)
			(layer "F.SilkS")
		)
		(fp_rect
			(start -5.4 -20.72)
			(end 15.58 4.45)
			(stroke
				(width 0.05)
				(type solid)
			)
			(fill no)
			(layer "F.CrtYd")
		)
		(fp_text user "License: Apache-2.0"
			(at -5.75 7.65 180)
			(layer "F.Fab")
			(effects
				(font
					(size 0.7 0.7)
					(thickness 0.15)
				)
				(justify left bottom)
			)
		)
		(fp_text user "${REFERENCE}"
			(at -5.75 6.45 180)
			(unlocked yes)
			(layer "F.Fab")
			(effects
				(font
					(size 0.7 0.7)
					(thickness 0.15)
				)
				(justify left bottom)
			)
		)
		(fp_text user "Author: Antmicro"
			(at -5.75 8.85 180)
			(layer "F.Fab")
			(effects
				(font
					(size 0.7 0.7)
					(thickness 0.15)
				)
				(justify left bottom)
			)
		)
		(pad "" np_thru_hole circle
			(at 0.245 -6.6 180)
			(size 3.2 3.2)
			(drill 3.2)
			(layers "*.Cu" "*.Mask")
		)
		(pad "" np_thru_hole circle
			(at 9.895 -6.6 180)
			(size 3.2 3.2)
			(drill 3.2)
			(layers "*.Cu" "*.Mask")
		)
		(pad "1" thru_hole circle
			(at 0 0 180)
			(size 1.39 1.39)
			(drill 0.89)
			(layers "*.Cu" "*.Mask")
			(remove_unused_layers no)
			(net 133 "/2xRJ45/P0_CT")
			(pinfunction "CT3")
			(pintype "bidirectional")
		)
		(pad "2" thru_hole circle
			(at 2.03 0 180)
			(size 1.39 1.39)
			(drill 0.89)
			(layers "*.Cu" "*.Mask")
			(remove_unused_layers no)
			(net 38 "/2xRJ45/Ethernet_P0.D3-")
			(pinfunction "T2-")
			(pintype "bidirectional")
		)
		(pad "3" thru_hole circle
			(at 4.06 0 180)
			(size 1.39 1.39)
			(drill 0.89)
			(layers "*.Cu" "*.Mask")
			(remove_unused_layers no)
			(net 44 "/2xRJ45/Ethernet_P0.D3+")
			(pinfunction "T2+")
			(pintype "bidirectional")
		)
		(pad "4" thru_hole circle
			(at 6.09 0 180)
			(size 1.39 1.39)
			(drill 0.89)
			(layers "*.Cu" "*.Mask")
			(remove_unused_layers no)
			(net 39 "/2xRJ45/Ethernet_P0.D2+")
			(pinfunction "T3+")
			(pintype "bidirectional")
		)
		(pad "5" thru_hole circle
			(at 8.12 0 180)
			(size 1.39 1.39)
			(drill 0.89)
			(layers "*.Cu" "*.Mask")
			(remove_unused_layers no)
			(net 36 "/2xRJ45/Ethernet_P0.D2-")
			(pinfunction "T3-")
			(pintype "bidirectional")
		)
		(pad "6" thru_hole circle
			(at 10.15 0 180)
			(size 1.39 1.39)
			(drill 0.89)
			(layers "*.Cu" "*.Mask")
			(remove_unused_layers no)
			(net 133 "/2xRJ45/P0_CT")
			(pinfunction "CT2")
			(pintype "bidirectional")
		)
		(pad "7" thru_hole circle
			(at -1.02 2.54 180)
			(size 1.39 1.39)
			(drill 0.89)
			(layers "*.Cu" "*.Mask")
			(remove_unused_layers no)
			(net 133 "/2xRJ45/P0_CT")
			(pinfunction "CT4")
			(pintype "bidirectional")
		)
		(pad "8" thru_hole circle
			(at 1.01 2.54 180)
			(size 1.39 1.39)
			(drill 0.89)
			(layers "*.Cu" "*.Mask")
			(remove_unused_layers no)
			(net 41 "/2xRJ45/Ethernet_P0.D4+")
			(pinfunction "T1+")
			(pintype "bidirectional")
		)
		(pad "9" thru_hole circle
			(at 3.04 2.54 180)
			(size 1.39 1.39)
			(drill 0.89)
			(layers "*.Cu" "*.Mask")
			(remove_unused_layers no)
			(net 43 "/2xRJ45/Ethernet_P0.D4-")
			(pinfunction "T1-")
			(pintype "bidirectional")
		)
		(pad "10" thru_hole circle
			(at 7.11 2.54 180)
			(size 1.39 1.39)
			(drill 0.89)
			(layers "*.Cu" "*.Mask")
			(remove_unused_layers no)
			(net 37 "/2xRJ45/Ethernet_P0.D1-")
			(pinfunction "T4-")
			(pintype "bidirectional")
		)
		(pad "11" thru_hole circle
			(at 9.14 2.54 180)
			(size 1.39 1.39)
			(drill 0.89)
			(layers "*.Cu" "*.Mask")
			(remove_unused_layers no)
			(net 42 "/2xRJ45/Ethernet_P0.D1+")
			(pinfunction "T4+")
			(pintype "bidirectional")
		)
		(pad "12" thru_hole circle
			(at 11.17 2.54 180)
			(size 1.39 1.39)
			(drill 0.89)
			(layers "*.Cu" "*.Mask")
			(remove_unused_layers no)
			(net 133 "/2xRJ45/P0_CT")
			(pinfunction "CT1")
			(pintype "bidirectional")
		)
		(pad "13" thru_hole circle
			(at 12.59 -12.95 180)
			(size 1.77 1.77)
			(drill 1.27)
			(layers "*.Cu" "*.Mask")
			(remove_unused_layers no)
			(net 410 "Net-(J3-LED_GRN-)")
			(pinfunction "LED_GRN-")
			(pintype "passive")
		)
		(pad "14" thru_hole circle
			(at 12.59 -15.49 180)
			(size 1.77 1.77)
			(drill 1.27)
			(layers "*.Cu" "*.Mask")
			(remove_unused_layers no)
			(net 7 "+3V3")
			(pinfunction "LED_GRN+")
			(pintype "passive")
		)
		(pad "15" thru_hole circle
			(at -2.45 -10.41 180)
			(size 1.77 1.77)
			(drill 1.27)
			(layers "*.Cu" "*.Mask")
			(remove_unused_layers no)
			(net 406 "Net-(J3-LED_YG_Y-)")
			(pinfunction "LED_YG_Y-")
			(pintype "passive")
		)
		(pad "16" thru_hole circle
			(at -2.45 -12.95 180)
			(size 1.77 1.77)
			(drill 1.27)
			(layers "*.Cu" "*.Mask")
			(remove_unused_layers no)
			(net 7 "+3V3")
			(pinfunction "LED_COM+")
			(pintype "passive")
		)
		(pad "17" thru_hole circle
			(at -2.45 -15.49 180)
			(size 1.77 1.77)
			(drill 1.27)
			(layers "*.Cu" "*.Mask")
			(remove_unused_layers no)
			(net 408 "Net-(J3-LED_YG_G-)")
			(pinfunction "LED_YG_G-")
			(pintype "passive")
		)
		(pad "SH" thru_hole circle
			(at -3.72 -6.6 180)
			(size 2.07 2.07)
			(drill 1.57)
			(layers "*.Cu" "*.Mask")
			(remove_unused_layers no)
			(net 23 "GND")
			(pinfunction "SHIELD")
			(pintype "passive")
		)
		(pad "SH" thru_hole circle
			(at 13.86 -6.6 180)
			(size 2.07 2.07)
			(drill 1.57)
			(layers "*.Cu" "*.Mask")
			(remove_unused_layers no)
			(net 23 "GND")
			(pinfunction "SHIELD")
			(pintype "passive")
		)
	)
	(footprint "antmicro-footprints:C_0402_1005Metric"
		(layer "F.Cu")
		(at 151.550002 109.150002)
		(descr "Capacitor SMD 0402")
		(tags "capacitor SMD 0402")
		(property "Reference" "C121"
			(at 14.149998 17.25 0)
			(layer "F.SilkS")
			(effects
				(font
					(size 0.7 0.7)
					(thickness 0.15)
				)
			)
		)
		(property "Value" "C_1u_25V_0402"
			(at -1.022927 2.155213 0)
			(layer "F.Fab")
			(effects
				(font
					(size 0.7 0.7)
					(thickness 0.15)
				)
				(justify left bottom)
			)
		)
		(property "Datasheet" "https://www.murata.com/products/productdetail?partno=GRM155R61E105KE11%23"
			(at 0 0 0)
			(layer "F.Fab")
			(hide yes)
			(effects
				(font
					(size 1.27 1.27)
					(thickness 0.15)
				)
			)
		)
		(property "Description" "SMD Multilayer Ceramic Capacitor, 1 µF, 25 V, 0402 [1005 Metric], ± 10%, X5R, GRM Series"
			(at 0 0 0)
			(layer "F.Fab")
			(hide yes)
			(effects
				(font
					(size 1.27 1.27)
					(thickness 0.15)
				)
			)
		)
		(property "MPN" "GRM155R61E105KE11J"
			(at 0 0 0)
			(unlocked yes)
			(layer "F.Fab")
			(hide yes)
			(effects
				(font
					(size 1 1)
					(thickness 0.15)
				)
			)
		)
		(property "Manufacturer" "Murata"
			(at 0 0 0)
			(unlocked yes)
			(layer "F.Fab")
			(hide yes)
			(effects
				(font
					(size 1 1)
					(thickness 0.15)
				)
			)
		)
		(property "License" "Apache-2.0"
			(at 0 0 0)
			(unlocked yes)
			(layer "F.Fab")
			(hide yes)
			(effects
				(font
					(size 1 1)
					(thickness 0.15)
				)
			)
		)
		(property "Author" "Antmicro"
			(at 0 0 0)
			(unlocked yes)
			(layer "F.Fab")
			(hide yes)
			(effects
				(font
					(size 1 1)
					(thickness 0.15)
				)
			)
		)
		(property "Val" "1u"
			(at 0 0 0)
			(unlocked yes)
			(layer "F.Fab")
			(hide yes)
			(effects
				(font
					(size 1 1)
					(thickness 0.15)
				)
			)
		)
		(property "Voltage" "25V"
			(at 0 0 0)
			(unlocked yes)
			(layer "F.Fab")
			(hide yes)
			(effects
				(font
					(size 1 1)
					(thickness 0.15)
				)
			)
		)
		(property "Dielectric" "X5R"
			(at 0 0 0)
			(unlocked yes)
			(layer "F.Fab")
			(hide yes)
			(effects
				(font
					(size 1 1)
					(thickness 0.15)
				)
			)
		)
		(sheetname "/X710 DCDC converters/")
		(sheetfile "DCDC_converters_X710.kicad_sch")
		(attr smd)
		(fp_rect
			(start -0.925 -0.47)
			(end 0.925 0.47)
			(stroke
				(width 0.05)
				(type default)
			)
			(fill no)
			(layer "F.CrtYd")
		)
		(fp_line
			(start -0.494 -0.25)
			(end 0.504 -0.25)
			(stroke
				(width 0.15)
				(type solid)
			)
			(layer "F.Fab")
		)
		(fp_line
			(start -0.494 0.248)
			(end -0.494 -0.25)
			(stroke
				(width 0.15)
				(type solid)
			)
			(layer "F.Fab")
		)
		(fp_line
			(start 0.504 -0.25)
			(end 0.504 0.248)
			(stroke
				(width 0.15)
				(type solid)
			)
			(layer "F.Fab")
		)
		(fp_line
			(start 0.504 0.248)
			(end -0.494 0.248)
			(stroke
				(width 0.15)
				(type solid)
			)
			(layer "F.Fab")
		)
		(fp_text user "Author: Antmicro"
			(at -0.939 3.399 0)
			(layer "F.Fab")
			(effects
				(font
					(size 0.7 0.7)
					(thickness 0.15)
				)
				(justify left bottom)
			)
		)
		(fp_text user "License: Apache-2.0"
			(at -0.939 5.799 0)
			(layer "F.Fab")
			(effects
				(font
					(size 0.7 0.7)
					(thickness 0.15)
				)
				(justify left bottom)
			)
		)
		(fp_text user "${REFERENCE}"
			(at -0.939 4.599 0)
			(layer "F.Fab")
			(effects
				(font
					(size 0.7 0.7)
					(thickness 0.15)
				)
				(justify left bottom)
			)
		)
		(pad "1" smd roundrect
			(at -0.48 0)
			(size 0.59 0.64)
			(layers "F.Cu" "F.Mask" "F.Paste")
			(roundrect_rratio 0.25)
			(net 23 "GND")
			(pintype "passive")
		)
		(pad "2" smd roundrect
			(at 0.48 0)
			(size 0.59 0.64)
			(layers "F.Cu" "F.Mask" "F.Paste")
			(roundrect_rratio 0.25)
			(net 108 "/X710 DCDC converters/1V88_VCC")
			(pintype "passive")
		)
	)
	(footprint "antmicro-footprints:R_0402_1005Metric"
		(layer "F.Cu")
		(at 125.02 86.5)
		(descr "Resistor SMD 0402")
		(tags "resistor SMD 0402")
		(property "Reference" "R120"
			(at -2.42 -0.509 0)
			(layer "F.SilkS")
			(effects
				(font
					(size 0.7 0.7)
					(thickness 0.15)
				)
				(justify left bottom)
			)
		)
		(property "Value" "R_8k2_0402"
			(at -1.011843 1.772047 0)
			(layer "F.Fab")
			(effects
				(font
					(size 0.7 0.7)
					(thickness 0.15)
				)
				(justify left bottom)
			)
		)
		(property "Datasheet" "https://www.bourns.com/docs/product-datasheets/cr.pdf"
			(at 0 0 0)
			(layer "F.Fab")
			(hide yes)
			(effects
				(font
					(size 1.27 1.27)
					(thickness 0.15)
				)
			)
		)
		(property "Description" "SMD Chip Resistor"
			(at 0 0 0)
			(layer "F.Fab")
			(hide yes)
			(effects
				(font
					(size 1.27 1.27)
					(thickness 0.15)
				)
			)
		)
		(property "MPN" "CR0402-FX-8201GLF"
			(at 0 0 0)
			(unlocked yes)
			(layer "F.Fab")
			(hide yes)
			(effects
				(font
					(size 1 1)
					(thickness 0.15)
				)
			)
		)
		(property "Manufacturer" "Bourns"
			(at 0 0 0)
			(unlocked yes)
			(layer "F.Fab")
			(hide yes)
			(effects
				(font
					(size 1 1)
					(thickness 0.15)
				)
			)
		)
		(property "License" "Apache-2.0"
			(at 0 0 0)
			(unlocked yes)
			(layer "F.Fab")
			(hide yes)
			(effects
				(font
					(size 1 1)
					(thickness 0.15)
				)
			)
		)
		(property "Author" "Antmicro"
			(at 0 0 0)
			(unlocked yes)
			(layer "F.Fab")
			(hide yes)
			(effects
				(font
					(size 1 1)
					(thickness 0.15)
				)
			)
		)
		(property "Val" "8k2"
			(at 0 0 0)
			(unlocked yes)
			(layer "F.Fab")
			(hide yes)
			(effects
				(font
					(size 1 1)
					(thickness 0.15)
				)
			)
		)
		(property "Tolerance" "1%"
			(at 0 0 0)
			(unlocked yes)
			(layer "F.Fab")
			(hide yes)
			(effects
				(font
					(size 1 1)
					(thickness 0.15)
				)
			)
		)
		(sheetname "/X710-AT2 PCIe/")
		(sheetfile "x710-at2-pcie.kicad_sch")
		(attr smd)
		(fp_rect
			(start -0.925 -0.47)
			(end 0.925 0.47)
			(stroke
				(width 0.05)
				(type default)
			)
			(fill no)
			(layer "F.CrtYd")
		)
		(fp_rect
			(start -0.5 -0.25)
			(end 0.5 0.25)
			(stroke
				(width 0.15)
				(type solid)
			)
			(fill no)
			(layer "F.Fab")
		)
		(fp_text user "License: Apache-2.0"
			(at -0.95 5.169 0)
			(layer "F.Fab")
			(effects
				(font
					(size 0.7 0.7)
					(thickness 0.15)
				)
				(justify left bottom)
			)
		)
		(fp_text user "Author: Antmicro"
			(at -0.95 4.169 0)
			(layer "F.Fab")
			(effects
				(font
					(size 0.7 0.7)
					(thickness 0.15)
				)
				(justify left bottom)
			)
		)
		(fp_text user "${REFERENCE}"
			(at -0.95 3.168 0)
			(layer "F.Fab")
			(effects
				(font
					(size 0.7 0.7)
					(thickness 0.15)
				)
				(justify left bottom)
			)
		)
		(pad "1" smd roundrect
			(at -0.48 0)
			(size 0.59 0.64)
			(layers "F.Cu" "F.Mask" "F.Paste")
			(roundrect_rratio 0.25)
			(net 23 "GND")
			(pintype "passive")
		)
		(pad "2" smd roundrect
			(at 0.48 0)
			(size 0.59 0.64)
			(layers "F.Cu" "F.Mask" "F.Paste")
			(roundrect_rratio 0.25)
			(net 15 "/X710-AT2 PCIe/PCIe_JTAG.~{JRST}")
			(pintype "passive")
		)
	)
)
